# S9S_MB_2U (Grand Teton) — schematic netlist excerpt (pin names and nets, part order shuffled) for the footprints in the layout excerpt that follows; sources: Cadence DE-HDL packaged netlist, KiCad conversion of 03242023_DA0F0TMBIJ0_F0T_Motherboard_J_brd_V01_OCP.brd

R1414  Q_RES  2K 1% CHIP  pkg 0402LF  page 219 : A = FM_PVCCD_HV_CPU1_EN ; B = GND
R1499  Q_RES  1K 1% CHIP  pkg 0402LF  page 200 : A = FM_BIOS_ADV_FUNCTIONS ; B = GND

DB13  TDR_3P  EMPTY  pkg TH2  page 309
  GND  = T1_GND
  IO1  = TDR_SE_40_OHM_IN5
  IO2  = TDR_SE_40_OHM_IN5

(kicad_pcb
	(version 20260206)
	(generator "pcbnew")
	(generator_version "10.0")
	(general
		(thickness 1.6)
		(legacy_teardrops no)
	)
	(paper "A4")
	(title_block
		(title "03242023_DA0F0TMBIJ0_F0T_Motherboard_J_brd_V01_OCP.brd")
		(comment 1 "Grand Teton / footprints 4704-4706 of 6105")
	)
	(layers
		(0 "F.Cu" signal "TOP")
		(4 "In1.Cu" signal "GND")
		(6 "In2.Cu" signal "IN1")
		(8 "In3.Cu" signal "GND1")
		(10 "In4.Cu" signal "IN2")
		(12 "In5.Cu" signal "GND2")
		(14 "In6.Cu" signal "IN3")
		(16 "In7.Cu" signal "GND3")
		(18 "In8.Cu" signal "VCC")
		(20 "In9.Cu" signal "VCC1")
		(22 "In10.Cu" signal "GND4")
		(24 "In11.Cu" signal "IN4")
		(26 "In12.Cu" signal "GND5")
		(28 "In13.Cu" signal "IN5")
		(30 "In14.Cu" signal "GND6")
		(32 "In15.Cu" signal "IN6")
		(34 "In16.Cu" signal "GND7")
		(2 "B.Cu" signal "BOTTOM")
		(9 "F.Adhes" user "F.Adhesive")
		(11 "B.Adhes" user "B.Adhesive")
		(13 "F.Paste" user "Package Geometry/Pastemask Top")
		(15 "B.Paste" user "Package Geometry/Pastemask Bottom")
		(5 "F.SilkS" user "Ref Des/Silkscreen Top")
		(7 "B.SilkS" user "Ref Des/Silkscreen Bottom")
		(1 "F.Mask" user "Board Geometry/Soldermask Top")
		(3 "B.Mask" user "Board Geometry/Soldermask Bottom")
		(17 "Dwgs.User" user "User.Drawings")
		(19 "Cmts.User" user "User.Comments")
		(21 "Eco1.User" user "User.Eco1")
		(23 "Eco2.User" user "User.Eco2")
		(25 "Edge.Cuts" user "Board Geometry/Outline")
		(27 "Margin" user)
		(31 "F.CrtYd" user "Package Geometry/Place Bound Top")
		(29 "B.CrtYd" user "Package Geometry/Place Bound Bottom")
		(35 "F.Fab" user "Ref Des/Assembly Top")
		(33 "B.Fab" user "Ref Des/Assembly Bottom")
	)
	(footprint ""
		(layer "B.Cu")
		(at 312.578242 -38.763448)
		(property "Reference" "R1499"
			(at 0 0 0)
			(layer "B.SilkS")
			(hide yes)
			(effects
				(font
					(size 1.27 1.27)
				)
				(justify mirror)
			)
		)
		(property "Value" ""
			(at 0 0 0)
			(layer "B.Fab")
			(effects
				(font
					(size 1.27 1.27)
				)
				(justify mirror)
			)
		)
		(duplicate_pad_numbers_are_jumpers no)
		(fp_line
			(start -0.7874 -0.4064)
			(end -0.7874 0.4064)
			(stroke
				(width 0.1524)
				(type default)
			)
			(layer "B.SilkS")
		)
		(fp_line
			(start -0.7874 0.4064)
			(end 0.7874 0.4064)
			(stroke
				(width 0.1524)
				(type default)
			)
			(layer "B.SilkS")
		)
		(fp_line
			(start 0.7874 -0.4064)
			(end -0.7874 -0.4064)
			(stroke
				(width 0.1524)
				(type default)
			)
			(layer "B.SilkS")
		)
		(fp_line
			(start 0.7874 0.4064)
			(end 0.7874 -0.4064)
			(stroke
				(width 0.1524)
				(type default)
			)
			(layer "B.SilkS")
		)
		(fp_line
			(start -0.67945 -0.3048)
			(end -0.67945 0.3048)
			(stroke
				(width 0.1)
				(type default)
			)
			(layer "B.Fab")
		)
		(fp_line
			(start -0.67945 0.3048)
			(end -0.120396 0.3048)
			(stroke
				(width 0.1)
				(type default)
			)
			(layer "B.Fab")
		)
		(fp_line
			(start -0.12065 -0.3048)
			(end -0.67945 -0.3048)
			(stroke
				(width 0.1)
				(type default)
			)
			(layer "B.Fab")
		)
		(fp_line
			(start -0.12065 -0.2794)
			(end -0.12065 -0.3048)
			(stroke
				(width 0.1)
				(type default)
			)
			(layer "B.Fab")
		)
		(fp_line
			(start -0.120396 0.2794)
			(end 0.12065 0.2794)
			(stroke
				(width 0.1)
				(type default)
			)
			(layer "B.Fab")
		)
		(fp_line
			(start -0.120396 0.3048)
			(end -0.120396 0.2794)
			(stroke
				(width 0.1)
				(type default)
			)
			(layer "B.Fab")
		)
		(fp_line
			(start 0.12065 -0.305054)
			(end 0.12065 -0.2794)
			(stroke
				(width 0.1)
				(type default)
			)
			(layer "B.Fab")
		)
		(fp_line
			(start 0.12065 -0.2794)
			(end -0.12065 -0.2794)
			(stroke
				(width 0.1)
				(type default)
			)
			(layer "B.Fab")
		)
		(fp_line
			(start 0.12065 0.2794)
			(end 0.12065 0.3048)
			(stroke
				(width 0.1)
				(type default)
			)
			(layer "B.Fab")
		)
		(fp_line
			(start 0.12065 0.3048)
			(end 0.67945 0.3048)
			(stroke
				(width 0.1)
				(type default)
			)
			(layer "B.Fab")
		)
		(fp_line
			(start 0.67945 -0.305054)
			(end 0.12065 -0.305054)
			(stroke
				(width 0.1)
				(type default)
			)
			(layer "B.Fab")
		)
		(fp_line
			(start 0.67945 0.3048)
			(end 0.67945 -0.305054)
			(stroke
				(width 0.1)
				(type default)
			)
			(layer "B.Fab")
		)
		(pad "1" smd circle
			(at 0.40005 0 180)
			(size 0 0)
			(layers "B.Cu" "B.Mask" "B.Paste")
			(net "FM_BIOS_ADV_FUNCTIONS")
		)
		(pad "2" smd circle
			(at -0.40005 0 180)
			(size 0 0)
			(layers "B.Cu" "B.Mask" "B.Paste")
			(net "GND")
		)
	)
	(footprint ""
		(layer "B.Cu")
		(at 500.77497 -427.51502 180)
		(property "Reference" "DB13"
			(at 2.443988 -8.440928 270)
			(unlocked yes)
			(layer "B.SilkS")
			(effects
				(font
					(size 0.7874 0.5842)
					(thickness 0.1524)
				)
				(justify left mirror)
			)
		)
		(property "Value" ""
			(at 0 0 0)
			(layer "B.Fab")
			(effects
				(font
					(size 1.27 1.27)
				)
				(justify mirror)
			)
		)
		(duplicate_pad_numbers_are_jumpers no)
		(fp_line
			(start 3.330702 -4.771136)
			(end -3.330702 -4.771136)
			(stroke
				(width 0.1524)
				(type default)
			)
			(layer "B.SilkS")
		)
		(fp_line
			(start 0 4.011168)
			(end 3.330702 -4.771136)
			(stroke
				(width 0.1524)
				(type default)
			)
			(layer "B.SilkS")
		)
		(fp_line
			(start -3.330702 -4.771136)
			(end 0 4.011168)
			(stroke
				(width 0.1524)
				(type default)
			)
			(layer "B.SilkS")
		)
		(fp_line
			(start 3.330702 -4.771136)
			(end -3.330702 -4.771136)
			(stroke
				(width 0.1)
				(type default)
			)
			(layer "B.Fab")
		)
		(fp_line
			(start 0 4.011168)
			(end 3.330702 -4.771136)
			(stroke
				(width 0.1)
				(type default)
			)
			(layer "B.Fab")
		)
		(fp_line
			(start -3.330702 -4.771136)
			(end 0 4.011168)
			(stroke
				(width 0.1)
				(type default)
			)
			(layer "B.Fab")
		)
		(pad "1" thru_hole circle
			(at 0 0)
			(size 2.159 2.159)
			(drill 1.7018)
			(layers "*.Cu" "*.Mask")
			(remove_unused_layers no)
			(net "T1_GND")
			(clearance 0.0254)
			(thermal_gap 0.0254)
		)
		(pad "2" thru_hole circle
			(at 1.27 -3.348736)
			(size 2.159 2.159)
			(drill 1.7018)
			(layers "*.Cu" "*.Mask")
			(remove_unused_layers no)
			(net "TDR_SE_40_OHM_IN5")
			(clearance 0.0254)
			(thermal_gap 0.0254)
		)
		(pad "3" thru_hole circle
			(at -1.27 -3.348736)
			(size 2.159 2.159)
			(drill 1.7018)
			(layers "*.Cu" "*.Mask")
			(remove_unused_layers no)
			(net "TDR_SE_40_OHM_IN5")
			(clearance 0.0254)
			(thermal_gap 0.0254)
		)
	)
	(footprint ""
		(layer "B.Cu")
		(at 164.64788 -122.646948)
		(property "Reference" "R1414"
			(at 0 0 0)
			(layer "B.SilkS")
			(hide yes)
			(effects
				(font
					(size 1.27 1.27)
				)
				(justify mirror)
			)
		)
		(property "Value" ""
			(at 0 0 0)
			(layer "B.Fab")
			(effects
				(font
					(size 1.27 1.27)
				)
				(justify mirror)
			)
		)
		(duplicate_pad_numbers_are_jumpers no)
		(fp_line
			(start -0.7874 -0.4064)
			(end -0.7874 0.4064)
			(stroke
				(width 0.1524)
				(type default)
			)
			(layer "B.SilkS")
		)
		(fp_line
			(start -0.7874 0.4064)
			(end 0.7874 0.4064)
			(stroke
				(width 0.1524)
				(type default)
			)
			(layer "B.SilkS")
		)
		(fp_line
			(start 0.7874 -0.4064)
			(end -0.7874 -0.4064)
			(stroke
				(width 0.1524)
				(type default)
			)
			(layer "B.SilkS")
		)
		(fp_line
			(start 0.7874 0.4064)
			(end 0.7874 -0.4064)
			(stroke
				(width 0.1524)
				(type default)
			)
			(layer "B.SilkS")
		)
		(fp_line
			(start -0.67945 -0.3048)
			(end -0.67945 0.3048)
			(stroke
				(width 0.1)
				(type default)
			)
			(layer "B.Fab")
		)
		(fp_line
			(start -0.67945 0.3048)
			(end -0.120396 0.3048)
			(stroke
				(width 0.1)
				(type default)
			)
			(layer "B.Fab")
		)
		(fp_line
			(start -0.12065 -0.3048)
			(end -0.67945 -0.3048)
			(stroke
				(width 0.1)
				(type default)
			)
			(layer "B.Fab")
		)
		(fp_line
			(start -0.12065 -0.2794)
			(end -0.12065 -0.3048)
			(stroke
				(width 0.1)
				(type default)
			)
			(layer "B.Fab")
		)
		(fp_line
			(start -0.120396 0.2794)
			(end 0.12065 0.2794)
			(stroke
				(width 0.1)
				(type default)
			)
			(layer "B.Fab")
		)
		(fp_line
			(start -0.120396 0.3048)
			(end -0.120396 0.2794)
			(stroke
				(width 0.1)
				(type default)
			)
			(layer "B.Fab")
		)
		(fp_line
			(start 0.12065 -0.305054)
			(end 0.12065 -0.2794)
			(stroke
				(width 0.1)
				(type default)
			)
			(layer "B.Fab")
		)
		(fp_line
			(start 0.12065 -0.2794)
			(end -0.12065 -0.2794)
			(stroke
				(width 0.1)
				(type default)
			)
			(layer "B.Fab")
		)
		(fp_line
			(start 0.12065 0.2794)
			(end 0.12065 0.3048)
			(stroke
				(width 0.1)
				(type default)
			)
			(layer "B.Fab")
		)
		(fp_line
			(start 0.12065 0.3048)
			(end 0.67945 0.3048)
			(stroke
				(width 0.1)
				(type default)
			)
			(layer "B.Fab")
		)
		(fp_line
			(start 0.67945 -0.305054)
			(end 0.12065 -0.305054)
			(stroke
				(width 0.1)
				(type default)
			)
			(layer "B.Fab")
		)
		(fp_line
			(start 0.67945 0.3048)
			(end 0.67945 -0.305054)
			(stroke
				(width 0.1)
				(type default)
			)
			(layer "B.Fab")
		)
		(pad "1" smd circle
			(at 0.40005 0 180)
			(size 0 0)
			(layers "B.Cu" "B.Mask" "B.Paste")
			(net "FM_PVCCD_HV_CPU1_EN")
		)
		(pad "2" smd circle
			(at -0.40005 0 180)
			(size 0 0)
			(layers "B.Cu" "B.Mask" "B.Paste")
			(net "GND")
		)
	)
)
